(kicad_pcb
	(version 20241229)
	(generator "pcbnew")
	(generator_version "9.0")
	(general
		(thickness 1.599998)
		(legacy_teardrops no)
	)
	(paper "A4")
	(title_block
		(title "Artix - Datacenter Secure Control Module (DC-SCM)")
		(date "2024-11-06")
		(rev "1.1.3")
		(comment 9 "footprints 367-372 of 544")
	)
	(layers
		(0 "F.Cu" signal)
		(4 "In1.Cu" signal)
		(6 "In2.Cu" signal)
		(8 "In3.Cu" signal)
		(10 "In4.Cu" signal)
		(12 "In5.Cu" signal)
		(14 "In6.Cu" signal)
		(2 "B.Cu" signal)
		(9 "F.Adhes" user "F.Adhesive")
		(11 "B.Adhes" user "B.Adhesive")
		(13 "F.Paste" user)
		(15 "B.Paste" user)
		(5 "F.SilkS" user "F.Silkscreen")
		(7 "B.SilkS" user "B.Silkscreen")
		(1 "F.Mask" user)
		(3 "B.Mask" user)
		(17 "Dwgs.User" user "User.Drawings")
		(19 "Cmts.User" user "User.Comments")
		(21 "Eco1.User" user "User.Eco1")
		(23 "Eco2.User" user "User.Eco2")
		(25 "Edge.Cuts" user)
		(27 "Margin" user)
		(31 "F.CrtYd" user "F.Courtyard")
		(29 "B.CrtYd" user "B.Courtyard")
		(35 "F.Fab" user)
		(33 "B.Fab" user)
	)
	(footprint "antmicro-footprints:R_0402_1005Metric"
		(layer "B.Cu")
		(at 106.4 102.9 -90)
		(descr "Resistor SMD 0402")
		(tags "resistor SMD 0402")
		(property "Reference" "R155"
			(at 0.7 -0.35 90)
			(layer "B.SilkS")
			(effects
				(font
					(size 0.7 0.7)
					(thickness 0.15)
				)
				(justify left bottom mirror)
			)
		)
		(property "Value" "R_4k7_0402"
			(at 0 -1.4 90)
			(layer "B.Fab")
			(effects
				(font
					(size 0.7 0.7)
					(thickness 0.15)
				)
				(justify left bottom mirror)
			)
		)
		(property "Datasheet" "https://www.bourns.com/docs/product-datasheets/cr.pdf"
			(at 0 0 270)
			(layer "F.Fab")
			(hide yes)
			(effects
				(font
					(size 1.27 1.27)
					(thickness 0.15)
				)
			)
		)
		(property "Description" "SMD Chip Resistor, 4.7 kohm, ± 1%, 62.5 mW, 0402 [1005 Metric], Thick Film, General Purpose"
			(at 0 0 270)
			(layer "F.Fab")
			(hide yes)
			(effects
				(font
					(size 1.27 1.27)
					(thickness 0.15)
				)
			)
		)
		(property "Author" "Antmicro"
			(at 3.5 209.3 0)
			(layer "B.Fab")
			(hide yes)
			(effects
				(font
					(size 1 1)
					(thickness 0.15)
				)
				(justify mirror)
			)
		)
		(property "License" "Apache-2.0"
			(at 3.5 209.3 0)
			(layer "B.Fab")
			(hide yes)
			(effects
				(font
					(size 1 1)
					(thickness 0.15)
				)
				(justify mirror)
			)
		)
		(property "MPN" "CR0402-FX-4701GLF"
			(at 3.5 209.3 0)
			(layer "B.Fab")
			(hide yes)
			(effects
				(font
					(size 1 1)
					(thickness 0.15)
				)
				(justify mirror)
			)
		)
		(property "Manufacturer" "Bourns"
			(at 3.5 209.3 0)
			(layer "B.Fab")
			(hide yes)
			(effects
				(font
					(size 1 1)
					(thickness 0.15)
				)
				(justify mirror)
			)
		)
		(property "Tolerance" "1%"
			(at 3.5 209.3 0)
			(layer "B.Fab")
			(hide yes)
			(effects
				(font
					(size 1 1)
					(thickness 0.15)
				)
				(justify mirror)
			)
		)
		(property "Val" "4k7"
			(at 3.5 209.3 0)
			(layer "B.Fab")
			(hide yes)
			(effects
				(font
					(size 1 1)
					(thickness 0.15)
				)
				(justify mirror)
			)
		)
		(sheetname "/Ethernet/")
		(sheetfile "ethernet.kicad_sch")
		(attr smd)
		(fp_rect
			(start -0.925 0.47)
			(end 0.925 -0.47)
			(stroke
				(width 0.05)
				(type default)
			)
			(fill no)
			(layer "B.CrtYd")
		)
		(fp_rect
			(start -0.5 0.25)
			(end 0.5 -0.25)
			(stroke
				(width 0.15)
				(type solid)
			)
			(fill no)
			(layer "B.Fab")
		)
		(pad "1" smd roundrect
			(at -0.48 0 270)
			(size 0.59 0.64)
			(layers "B.Cu" "B.Mask" "B.Paste")
			(roundrect_rratio 0.25)
			(net 142 "ETH_MDIO")
			(pintype "passive")
		)
		(pad "2" smd roundrect
			(at 0.48 0 270)
			(size 0.59 0.64)
			(layers "B.Cu" "B.Mask" "B.Paste")
			(roundrect_rratio 0.25)
			(net 2 "VCC3V3")
			(pintype "passive")
		)
	)
	(footprint "antmicro-footprints:C_0402_1005Metric"
		(layer "B.Cu")
		(at 110.78 86.955 90)
		(descr "Capacitor SMD 0402")
		(tags "capacitor SMD 0402")
		(property "Reference" "C225"
			(at -1.045 2.32 90)
			(layer "B.SilkS")
			(effects
				(font
					(size 0.7 0.7)
					(thickness 0.15)
				)
				(justify right bottom mirror)
			)
		)
		(property "Value" "C_100n_0402"
			(at 0 -1.4 90)
			(layer "B.Fab")
			(effects
				(font
					(size 0.7 0.7)
					(thickness 0.15)
				)
				(justify right bottom mirror)
			)
		)
		(property "Datasheet" "https://www.murata.com/products/productdetail?partno=GRM155R61H104KE14%23"
			(at 0 0 90)
			(layer "F.Fab")
			(hide yes)
			(effects
				(font
					(size 1.27 1.27)
					(thickness 0.15)
				)
			)
		)
		(property "Description" "SMD Multilayer Ceramic Capacitor, 0.1 µF, 50 V, 0402 [1005 Metric], ± 10%, X5R, GRM Series"
			(at 0 0 90)
			(layer "F.Fab")
			(hide yes)
			(effects
				(font
					(size 1.27 1.27)
					(thickness 0.15)
				)
			)
		)
		(property "Author" "Antmicro"
			(at 197.735 -23.825 0)
			(layer "B.Fab")
			(hide yes)
			(effects
				(font
					(size 1 1)
					(thickness 0.15)
				)
				(justify mirror)
			)
		)
		(property "Dielectric" "X5R"
			(at 197.735 -23.825 0)
			(layer "B.Fab")
			(hide yes)
			(effects
				(font
					(size 1 1)
					(thickness 0.15)
				)
				(justify mirror)
			)
		)
		(property "License" "Apache-2.0"
			(at 197.735 -23.825 0)
			(layer "B.Fab")
			(hide yes)
			(effects
				(font
					(size 1 1)
					(thickness 0.15)
				)
				(justify mirror)
			)
		)
		(property "MPN" "GRM155R61H104KE14D"
			(at 197.735 -23.825 0)
			(layer "B.Fab")
			(hide yes)
			(effects
				(font
					(size 1 1)
					(thickness 0.15)
				)
				(justify mirror)
			)
		)
		(property "Manufacturer" "Murata"
			(at 197.735 -23.825 0)
			(layer "B.Fab")
			(hide yes)
			(effects
				(font
					(size 1 1)
					(thickness 0.15)
				)
				(justify mirror)
			)
		)
		(property "Val" "100n"
			(at 197.735 -23.825 0)
			(layer "B.Fab")
			(hide yes)
			(effects
				(font
					(size 1 1)
					(thickness 0.15)
				)
				(justify mirror)
			)
		)
		(property "Voltage" "50V"
			(at 197.735 -23.825 0)
			(layer "B.Fab")
			(hide yes)
			(effects
				(font
					(size 1 1)
					(thickness 0.15)
				)
				(justify mirror)
			)
		)
		(sheetname "/Ethernet/")
		(sheetfile "ethernet.kicad_sch")
		(attr smd)
		(fp_rect
			(start -0.925 0.47)
			(end 0.925 -0.47)
			(stroke
				(width 0.05)
				(type default)
			)
			(fill no)
			(layer "B.CrtYd")
		)
		(fp_line
			(start 0.504 -0.248)
			(end -0.494 -0.248)
			(stroke
				(width 0.15)
				(type solid)
			)
			(layer "B.Fab")
		)
		(fp_line
			(start -0.494 -0.248)
			(end -0.494 0.25)
			(stroke
				(width 0.15)
				(type solid)
			)
			(layer "B.Fab")
		)
		(fp_line
			(start 0.504 0.25)
			(end 0.504 -0.248)
			(stroke
				(width 0.15)
				(type solid)
			)
			(layer "B.Fab")
		)
		(fp_line
			(start -0.494 0.25)
			(end 0.504 0.25)
			(stroke
				(width 0.15)
				(type solid)
			)
			(layer "B.Fab")
		)
		(pad "1" smd roundrect
			(at -0.48 0 90)
			(size 0.59 0.64)
			(layers "B.Cu" "B.Mask" "B.Paste")
			(roundrect_rratio 0.25)
			(net 1 "GND")
			(pintype "passive")
		)
		(pad "2" smd roundrect
			(at 0.48 0 90)
			(size 0.59 0.64)
			(layers "B.Cu" "B.Mask" "B.Paste")
			(roundrect_rratio 0.25)
			(net 202 "Net-(J1-TRCT1)")
			(pintype "passive")
		)
	)
	(footprint "antmicro-footprints:C_0402_1005Metric"
		(layer "B.Cu")
		(at 111.78 86.94 90)
		(descr "Capacitor SMD 0402")
		(tags "capacitor SMD 0402")
		(property "Reference" "C226"
			(at -1.045 2.32 90)
			(layer "B.SilkS")
			(effects
				(font
					(size 0.7 0.7)
					(thickness 0.15)
				)
				(justify right bottom mirror)
			)
		)
		(property "Value" "C_100n_0402"
			(at 0 -1.4 90)
			(layer "B.Fab")
			(effects
				(font
					(size 0.7 0.7)
					(thickness 0.15)
				)
				(justify right bottom mirror)
			)
		)
		(property "Datasheet" "https://www.murata.com/products/productdetail?partno=GRM155R61H104KE14%23"
			(at 0 0 90)
			(layer "F.Fab")
			(hide yes)
			(effects
				(font
					(size 1.27 1.27)
					(thickness 0.15)
				)
			)
		)
		(property "Description" "SMD Multilayer Ceramic Capacitor, 0.1 µF, 50 V, 0402 [1005 Metric], ± 10%, X5R, GRM Series"
			(at 0 0 90)
			(layer "F.Fab")
			(hide yes)
			(effects
				(font
					(size 1.27 1.27)
					(thickness 0.15)
				)
			)
		)
		(property "Author" "Antmicro"
			(at 198.72 -24.84 0)
			(layer "B.Fab")
			(hide yes)
			(effects
				(font
					(size 1 1)
					(thickness 0.15)
				)
				(justify mirror)
			)
		)
		(property "Dielectric" "X5R"
			(at 198.72 -24.84 0)
			(layer "B.Fab")
			(hide yes)
			(effects
				(font
					(size 1 1)
					(thickness 0.15)
				)
				(justify mirror)
			)
		)
		(property "License" "Apache-2.0"
			(at 198.72 -24.84 0)
			(layer "B.Fab")
			(hide yes)
			(effects
				(font
					(size 1 1)
					(thickness 0.15)
				)
				(justify mirror)
			)
		)
		(property "MPN" "GRM155R61H104KE14D"
			(at 198.72 -24.84 0)
			(layer "B.Fab")
			(hide yes)
			(effects
				(font
					(size 1 1)
					(thickness 0.15)
				)
				(justify mirror)
			)
		)
		(property "Manufacturer" "Murata"
			(at 198.72 -24.84 0)
			(layer "B.Fab")
			(hide yes)
			(effects
				(font
					(size 1 1)
					(thickness 0.15)
				)
				(justify mirror)
			)
		)
		(property "Val" "100n"
			(at 198.72 -24.84 0)
			(layer "B.Fab")
			(hide yes)
			(effects
				(font
					(size 1 1)
					(thickness 0.15)
				)
				(justify mirror)
			)
		)
		(property "Voltage" "50V"
			(at 198.72 -24.84 0)
			(layer "B.Fab")
			(hide yes)
			(effects
				(font
					(size 1 1)
					(thickness 0.15)
				)
				(justify mirror)
			)
		)
		(sheetname "/Ethernet/")
		(sheetfile "ethernet.kicad_sch")
		(attr smd)
		(fp_rect
			(start -0.925 0.47)
			(end 0.925 -0.47)
			(stroke
				(width 0.05)
				(type default)
			)
			(fill no)
			(layer "B.CrtYd")
		)
		(fp_line
			(start 0.504 -0.248)
			(end -0.494 -0.248)
			(stroke
				(width 0.15)
				(type solid)
			)
			(layer "B.Fab")
		)
		(fp_line
			(start -0.494 -0.248)
			(end -0.494 0.25)
			(stroke
				(width 0.15)
				(type solid)
			)
			(layer "B.Fab")
		)
		(fp_line
			(start 0.504 0.25)
			(end 0.504 -0.248)
			(stroke
				(width 0.15)
				(type solid)
			)
			(layer "B.Fab")
		)
		(fp_line
			(start -0.494 0.25)
			(end 0.504 0.25)
			(stroke
				(width 0.15)
				(type solid)
			)
			(layer "B.Fab")
		)
		(pad "1" smd roundrect
			(at -0.48 0 90)
			(size 0.59 0.64)
			(layers "B.Cu" "B.Mask" "B.Paste")
			(roundrect_rratio 0.25)
			(net 1 "GND")
			(pintype "passive")
		)
		(pad "2" smd roundrect
			(at 0.48 0 90)
			(size 0.59 0.64)
			(layers "B.Cu" "B.Mask" "B.Paste")
			(roundrect_rratio 0.25)
			(net 203 "Net-(J1-TRCT2)")
			(pintype "passive")
		)
	)
	(footprint "antmicro-footprints:C_0402_1005Metric"
		(layer "B.Cu")
		(at 97.57 87.005 90)
		(descr "Capacitor SMD 0402")
		(tags "capacitor SMD 0402")
		(property "Reference" "C227"
			(at 1.005 -1.07 90)
			(layer "B.SilkS")
			(effects
				(font
					(size 0.7 0.7)
					(thickness 0.15)
				)
				(justify right bottom mirror)
			)
		)
		(property "Value" "C_100n_0402"
			(at 0 -1.4 90)
			(layer "B.Fab")
			(effects
				(font
					(size 0.7 0.7)
					(thickness 0.15)
				)
				(justify right bottom mirror)
			)
		)
		(property "Datasheet" "https://www.murata.com/products/productdetail?partno=GRM155R61H104KE14%23"
			(at 0 0 90)
			(layer "F.Fab")
			(hide yes)
			(effects
				(font
					(size 1.27 1.27)
					(thickness 0.15)
				)
			)
		)
		(property "Description" "SMD Multilayer Ceramic Capacitor, 0.1 µF, 50 V, 0402 [1005 Metric], ± 10%, X5R, GRM Series"
			(at 0 0 90)
			(layer "F.Fab")
			(hide yes)
			(effects
				(font
					(size 1.27 1.27)
					(thickness 0.15)
				)
			)
		)
		(property "Author" "Antmicro"
			(at 184.575 -10.565 0)
			(layer "B.Fab")
			(hide yes)
			(effects
				(font
					(size 1 1)
					(thickness 0.15)
				)
				(justify mirror)
			)
		)
		(property "Dielectric" "X5R"
			(at 184.575 -10.565 0)
			(layer "B.Fab")
			(hide yes)
			(effects
				(font
					(size 1 1)
					(thickness 0.15)
				)
				(justify mirror)
			)
		)
		(property "License" "Apache-2.0"
			(at 184.575 -10.565 0)
			(layer "B.Fab")
			(hide yes)
			(effects
				(font
					(size 1 1)
					(thickness 0.15)
				)
				(justify mirror)
			)
		)
		(property "MPN" "GRM155R61H104KE14D"
			(at 184.575 -10.565 0)
			(layer "B.Fab")
			(hide yes)
			(effects
				(font
					(size 1 1)
					(thickness 0.15)
				)
				(justify mirror)
			)
		)
		(property "Manufacturer" "Murata"
			(at 184.575 -10.565 0)
			(layer "B.Fab")
			(hide yes)
			(effects
				(font
					(size 1 1)
					(thickness 0.15)
				)
				(justify mirror)
			)
		)
		(property "Val" "100n"
			(at 184.575 -10.565 0)
			(layer "B.Fab")
			(hide yes)
			(effects
				(font
					(size 1 1)
					(thickness 0.15)
				)
				(justify mirror)
			)
		)
		(property "Voltage" "50V"
			(at 184.575 -10.565 0)
			(layer "B.Fab")
			(hide yes)
			(effects
				(font
					(size 1 1)
					(thickness 0.15)
				)
				(justify mirror)
			)
		)
		(sheetname "/Ethernet/")
		(sheetfile "ethernet.kicad_sch")
		(attr smd)
		(fp_rect
			(start -0.925 0.47)
			(end 0.925 -0.47)
			(stroke
				(width 0.05)
				(type default)
			)
			(fill no)
			(layer "B.CrtYd")
		)
		(fp_line
			(start 0.504 -0.248)
			(end -0.494 -0.248)
			(stroke
				(width 0.15)
				(type solid)
			)
			(layer "B.Fab")
		)
		(fp_line
			(start -0.494 -0.248)
			(end -0.494 0.25)
			(stroke
				(width 0.15)
				(type solid)
			)
			(layer "B.Fab")
		)
		(fp_line
			(start 0.504 0.25)
			(end 0.504 -0.248)
			(stroke
				(width 0.15)
				(type solid)
			)
			(layer "B.Fab")
		)
		(fp_line
			(start -0.494 0.25)
			(end 0.504 0.25)
			(stroke
				(width 0.15)
				(type solid)
			)
			(layer "B.Fab")
		)
		(pad "1" smd roundrect
			(at -0.48 0 90)
			(size 0.59 0.64)
			(layers "B.Cu" "B.Mask" "B.Paste")
			(roundrect_rratio 0.25)
			(net 1 "GND")
			(pintype "passive")
		)
		(pad "2" smd roundrect
			(at 0.48 0 90)
			(size 0.59 0.64)
			(layers "B.Cu" "B.Mask" "B.Paste")
			(roundrect_rratio 0.25)
			(net 204 "Net-(J1-TRCT3)")
			(pintype "passive")
		)
	)
	(footprint "antmicro-footprints:R_0402_1005Metric"
		(layer "B.Cu")
		(at 108.3 102.9 -90)
		(descr "Resistor SMD 0402")
		(tags "resistor SMD 0402")
		(property "Reference" "R156"
			(at 0.7 -0.35 90)
			(layer "B.SilkS")
			(effects
				(font
					(size 0.7 0.7)
					(thickness 0.15)
				)
				(justify left bottom mirror)
			)
		)
		(property "Value" "R_10k2_0402"
			(at 0 -1.4 90)
			(layer "B.Fab")
			(effects
				(font
					(size 0.7 0.7)
					(thickness 0.15)
				)
				(justify left bottom mirror)
			)
		)
		(property "Datasheet" "https://www.bourns.com/docs/product-datasheets/cr.pdf"
			(at 0 0 270)
			(layer "F.Fab")
			(hide yes)
			(effects
				(font
					(size 1.27 1.27)
					(thickness 0.15)
				)
			)
		)
		(property "Description" "SMD Chip Resistor"
			(at 0 0 270)
			(layer "F.Fab")
			(hide yes)
			(effects
				(font
					(size 1.27 1.27)
					(thickness 0.15)
				)
			)
		)
		(property "Author" "Antmicro"
			(at 5.4 211.2 0)
			(layer "B.Fab")
			(hide yes)
			(effects
				(font
					(size 1 1)
					(thickness 0.15)
				)
				(justify mirror)
			)
		)
		(property "License" "Apache-2.0"
			(at 5.4 211.2 0)
			(layer "B.Fab")
			(hide yes)
			(effects
				(font
					(size 1 1)
					(thickness 0.15)
				)
				(justify mirror)
			)
		)
		(property "MPN" "CR0402-FX-1022GLF"
			(at 5.4 211.2 0)
			(layer "B.Fab")
			(hide yes)
			(effects
				(font
					(size 1 1)
					(thickness 0.15)
				)
				(justify mirror)
			)
		)
		(property "Manufacturer" "Bourns"
			(at 5.4 211.2 0)
			(layer "B.Fab")
			(hide yes)
			(effects
				(font
					(size 1 1)
					(thickness 0.15)
				)
				(justify mirror)
			)
		)
		(property "Tolerance" "1%"
			(at 5.4 211.2 0)
			(layer "B.Fab")
			(hide yes)
			(effects
				(font
					(size 1 1)
					(thickness 0.15)
				)
				(justify mirror)
			)
		)
		(property "Val" "10k2"
			(at 5.4 211.2 0)
			(layer "B.Fab")
			(hide yes)
			(effects
				(font
					(size 1 1)
					(thickness 0.15)
				)
				(justify mirror)
			)
		)
		(sheetname "/Ethernet/")
		(sheetfile "ethernet.kicad_sch")
		(attr smd)
		(fp_rect
			(start -0.925 0.47)
			(end 0.925 -0.47)
			(stroke
				(width 0.05)
				(type default)
			)
			(fill no)
			(layer "B.CrtYd")
		)
		(fp_rect
			(start -0.5 0.25)
			(end 0.5 -0.25)
			(stroke
				(width 0.15)
				(type solid)
			)
			(fill no)
			(layer "B.Fab")
		)
		(pad "1" smd roundrect
			(at -0.48 0 270)
			(size 0.59 0.64)
			(layers "B.Cu" "B.Mask" "B.Paste")
			(roundrect_rratio 0.25)
			(net 414 "ETH_~{RESET}")
			(pintype "passive")
		)
		(pad "2" smd roundrect
			(at 0.48 0 270)
			(size 0.59 0.64)
			(layers "B.Cu" "B.Mask" "B.Paste")
			(roundrect_rratio 0.25)
			(net 2 "VCC3V3")
			(pintype "passive")
		)
	)
	(footprint "antmicro-footprints:C_0402_1005Metric"
		(layer "B.Cu")
		(at 123.88625 113.475 -90)
		(descr "Capacitor SMD 0402")
		(tags "capacitor SMD 0402")
		(property "Reference" "C20"
			(at 0.825 -0.31375 90)
			(layer "B.SilkS")
			(effects
				(font
					(size 0.7 0.7)
					(thickness 0.15)
				)
				(justify left bottom mirror)
			)
		)
		(property "Value" "C_100n_0402"
			(at 0 -1.4 90)
			(layer "B.Fab")
			(effects
				(font
					(size 0.7 0.7)
					(thickness 0.15)
				)
				(justify left bottom mirror)
			)
		)
		(property "Datasheet" "https://www.murata.com/products/productdetail?partno=GRM155R61H104KE14%23"
			(at 0 0 270)
			(layer "F.Fab")
			(hide yes)
			(effects
				(font
					(size 1.27 1.27)
					(thickness 0.15)
				)
			)
		)
		(property "Description" "SMD Multilayer Ceramic Capacitor, 0.1 µF, 50 V, 0402 [1005 Metric], ± 10%, X5R, GRM Series"
			(at 0 0 270)
			(layer "F.Fab")
			(hide yes)
			(effects
				(font
					(size 1.27 1.27)
					(thickness 0.15)
				)
			)
		)
		(property "Author" "Antmicro"
			(at 10.41125 237.36125 0)
			(layer "B.Fab")
			(hide yes)
			(effects
				(font
					(size 1 1)
					(thickness 0.15)
				)
				(justify mirror)
			)
		)
		(property "Dielectric" "X5R"
			(at 10.41125 237.36125 0)
			(layer "B.Fab")
			(hide yes)
			(effects
				(font
					(size 1 1)
					(thickness 0.15)
				)
				(justify mirror)
			)
		)
		(property "License" "Apache-2.0"
			(at 10.41125 237.36125 0)
			(layer "B.Fab")
			(hide yes)
			(effects
				(font
					(size 1 1)
					(thickness 0.15)
				)
				(justify mirror)
			)
		)
		(property "MPN" "GRM155R61H104KE14D"
			(at 10.41125 237.36125 0)
			(layer "B.Fab")
			(hide yes)
			(effects
				(font
					(size 1 1)
					(thickness 0.15)
				)
				(justify mirror)
			)
		)
		(property "Manufacturer" "Murata"
			(at 10.41125 237.36125 0)
			(layer "B.Fab")
			(hide yes)
			(effects
				(font
					(size 1 1)
					(thickness 0.15)
				)
				(justify mirror)
			)
		)
		(property "Val" "100n"
			(at 10.41125 237.36125 0)
			(layer "B.Fab")
			(hide yes)
			(effects
				(font
					(size 1 1)
					(thickness 0.15)
				)
				(justify mirror)
			)
		)
		(property "Voltage" "50V"
			(at 10.41125 237.36125 0)
			(layer "B.Fab")
			(hide yes)
			(effects
				(font
					(size 1 1)
					(thickness 0.15)
				)
				(justify mirror)
			)
		)
		(sheetname "/Interfaces/")
		(sheetfile "interfaces.kicad_sch")
		(attr smd)
		(fp_rect
			(start -0.925 0.47)
			(end 0.925 -0.47)
			(stroke
				(width 0.05)
				(type default)
			)
			(fill no)
			(layer "B.CrtYd")
		)
		(fp_line
			(start -0.494 0.25)
			(end 0.504 0.25)
			(stroke
				(width 0.15)
				(type solid)
			)
			(layer "B.Fab")
		)
		(fp_line
			(start 0.504 0.25)
			(end 0.504 -0.248)
			(stroke
				(width 0.15)
				(type solid)
			)
			(layer "B.Fab")
		)
		(fp_line
			(start -0.494 -0.248)
			(end -0.494 0.25)
			(stroke
				(width 0.15)
				(type solid)
			)
			(layer "B.Fab")
		)
		(fp_line
			(start 0.504 -0.248)
			(end -0.494 -0.248)
			(stroke
				(width 0.15)
				(type solid)
			)
			(layer "B.Fab")
		)
		(pad "1" smd roundrect
			(at -0.48 0 270)
			(size 0.59 0.64)
			(layers "B.Cu" "B.Mask" "B.Paste")
			(roundrect_rratio 0.25)
			(net 1 "GND")
			(pintype "passive")
		)
		(pad "2" smd roundrect
			(at 0.48 0 270)
			(size 0.59 0.64)
			(layers "B.Cu" "B.Mask" "B.Paste")
			(roundrect_rratio 0.25)
			(net 105 "Net-(C20-Pad2)")
			(pintype "passive")
		)
	)
)
